# Barreleye-G2_Tri-mode BPX24-DVT-X01-SKU-BOM-X07-20171222_Final.xls.xlsx — SKU1 (bom)
| FOXCONN TECHNOLOGY GROUP |  |  |  |  |  |  |  |  |  |  |  |  |  |  |  |  |  |  |  |
| BILL OF MATERIAL |  |  |  |  |  |  |  |  |  |  |  |  |  |  |  |  |  |  |  |
| REV OF  BOM |  | CUSTOMER |  | <name> |  | CUSTOMER P/N |  | AA P/N：1A42NC500-600-1 | PWA DESCRIPTION |  |  |  | PRODUCT CODE |  |  | PWA  REV |  | DATE |  |
| Sourcing (Single/Sole/Multi) | Critical Commodity (Y or N) | Component Class (1, 2, other) | Customer PSL (Y or N) | Line Item | Item Number | Foxconn P/N | Customer P/N | Part Description | Manufacturer  Full Name | Manufacturer  Part Number | Qty | RoHS Status | Location | CC Qual Build: | Qual by (Customer / ODM ?) | The Date of Change Part or Add 2nd Source | Configuration Identifier | Customer Comments | ODM Comments |
|  |  |  |  | 1 | 1 | 0101FGA00-000-G |  | PCB,Zaius-Tri-mode BPX24 DVT-X01,OSP,Blu,22L,21.122*3.470,G | GOLD CIRCUIT ELECTRONICS LTD. | 0101FGA00-000-G | 1 | G | PCB |  |  |  |  |  |  |
|  |  |  |  |  | 1 | 0101FGA00-000-G |  | PCB,Zaius-Tri-mode BPX24 DVT-X01,OSP,Blu,22L,21.122*3.470,G | ZHUHAI FOUNDER PRINTED CIRCUIT BOARD（HK） DEVELOPMENT LIMITED | 0101FGA00-000-G |  | G |  |  |  |  |  |  |  |
|  |  |  |  | 2 | 2 | 62111EC00-021-G |  | ECAP,680uF,+/-20%,16V,105℃,G,SMD10*10,ESR<=80mOhm | NIPPON CHEMI-CON CORPORATION | EMZA160ADA681MJA0G | 1 | G | CE1 |  |  |  |  |  |  |
|  |  |  |  | 3 | 3 | 620101T02-015-G | - | CAP,100nF,+/-10%,X7R,16V,G,SMD0402 | MURATA ELEC. NORTH AMERICA | GRM155R71C104K | 145 | G | PSTC1,PFTC1,PETC1,C1,C2,C6,C8,C9,PSRC10,C10,C15,C19,C119,C123,C125,C129,C155,C159,C161,C165,C167,C171,C173,C177,C179,C183,C185,C189,C191,C192,C193,C194,C196,C198,C201,C207,C216,C217,C224,C249,C253,C255,C259,C261,C265,C267,C271,C273,C277,C279,C283,C285,C289,C291,C295,C297,C301,C303,C307,C309,C313,C315,C319,C321,C325,C327,C331,C333,C337,C339,C343,C397,C2101,C2102,C2103,C2104,C2105,C2106,C2107,C2108,C2109,C2110,C2111,C2112,C2113,C2114,C2115,C2116,C2117,C2118,C2119,C2120,C2121,C2122,C2123,C2124,C2125,C2126,C2127,C2128,C2129,C2130,C2131,C2132,C2133,C2134,C2135,C2136,C2137,C2138,C2139,C2140,C2141,C2143,C2145,C2147,C2149,C2169,C2171,C2176,C2177,C2178,C2232,C2233,C2234,C2235,C2237,C2239,C2240,C2241,C2242,C2254,C2255,C2256,C2259,C2260,C2261,C2262,C2263,C2264,C2265,C2266,C2270,C2271,C2272 |  |  |  |  |  |  |
|  |  |  |  |  | 3 | 620101T00-012-G |  | CAP,100nF,+/-10%,X7R,16V,G,SMD0402 | WALSIN TECHNOLOGY CORPORATION | 0402B104K160CT |  | G |  |  |  |  |  |  |  |
|  |  |  |  |  | 3 | 620101T00-026-G |  | CAP,100nF,+/-10%,X7R,16V,G,SMD0402 | SAMSUNG SEMICONDUCTOR | CL05B104KO5NNNC |  | G |  |  |  |  |  |  |  |
|  |  |  |  |  | 3 | 620101T00-015-G |  | CAP,100nF,+/-10%,X7R,16V,G,SMD0402 | MURATA ELEC. NORTH AMERICA | GRM155R71C104KA88D |  | G |  |  |  |  |  |  |  |
|  |  |  |  | 4 | 4 | 620100A00-015-G | - | CAP,10uF,+/-10%,X5R,16V,G,SMD1206 | MURATA ELEC. NORTH AMERICA | GRM31CR61C106K | 30 | G | C3,C4,C5,C7,C120,C128,C158,C164,C170,C176,C182,C188,C252,C258,C264,C270,C276,C282,C288,C294,C300,C306,C312,C318,C324,C330,C336,C342,C2236,C2238 |  |  |  |  |  |  |
|  |  |  |  |  | 4 | 620100A00-026-G |  | CAP,10uF,+/-10%,X5R,16V,G,SMD1206 | SAMSUNG SEMICONDUCTOR | CL31A106KOHNNNE |  | G |  |  |  |  |  |  |  |
|  |  |  |  |  | 4 | 620100A03-023-G |  | CAP,10uF,+/-10%,X5R,16V,G,SMD1206 | TAIYO ELECTRIC IND.CO.LTD | EMK316BJ106KL-T |  | G |  |  |  |  |  |  |  |
|  |  |  |  |  | 4 | 620100A00-012-G |  | CAP,10uF,+/-10%,X5R,16V,G,SMD1206 | WALSIN TECHNOLOGY CORPORATION | 1206X106K160CT |  | G |  |  |  |  |  |  |  |
|  |  |  |  |  | 4 | 620100A00-011-G |  | CAP,10uF,+/-10%,X5R,16V,G,SMD1206 | YAGEO CORPORATION COMPONENT | CC1206KKX5R7BB106 |  | G |  |  |  |  |  |  |  |
|  |  |  |  | 5 | 5 | 620117N00-015-G | - | CAP,22uF,+/-10%,X5R,16V,G,SMD1206 | MURATA ELEC. NORTH AMERICA | GRM31CR61C226K | 48 | G | C121,C122,C126,C130,C156,C160,C162,C166,C168,C172,C174,C178,C180,C184,C186,C190,C250,C254,C256,C260,C262,C266,C268,C272,C274,C278,C280,C284,C286,C290,C292,C296,C298,C302,C304,C308,C310,C314,C316,C320,C322,C326,C328,C332,C334,C338,C340,C344 |  |  |  |  |  |  |
|  |  |  |  |  | 5 | 620117N00-023-G |  | CAP,22uF,+/-10%,X5R,16V,G,SMD1206 | TAIYO ELECTRIC IND.CO.LTD | EMK316BJ226KL-T |  | G |  |  |  |  |  |  |  |
|  |  |  |  |  | 5 | 620117N01-026-G |  | CAP,22uF,+/-10%,X5R,16V,G,SMD1206 | SAMSUNG SEMICONDUCTOR | CL31A226KOHNNNE |  | G |  |  |  |  |  |  |  |
|  |  |  |  | 6 | 6 | 620108H00-015-G | - | CAP,22uF,+/-20%,X5R,6.3V,G,SMD0805 | MURATA ELEC. NORTH AMERICA | GRM21BR60J226M | 24 | G | C124,C127,C157,C163,C169,C175,C181,C187,C251,C257,C263,C269,C275,C281,C287,C293,C299,C305,C311,C317,C323,C329,C335,C341 |  |  |  |  |  |  |
|  |  |  |  |  | 6 | 620108H04-023-G |  | CAP,22uF,+/-20%,X5R,6.3V,G,SMD0805 | TAIYO ELECTRIC IND.CO.LTD | JMK212BJ226MG-T |  | G |  |  |  |  |  |  |  |
|  |  |  |  |  | 6 | 620108H00-026-G |  | CAP,22uF,+/-20%,X5R,6.3V,G,SMD0805 | SAMSUNG SEMICONDUCTOR | CL21A226MQQNNNE |  | G |  |  |  |  |  |  |  |
|  |  |  |  |  | 6 | 620108H00-011-G |  | CAP,22uF,+/-20%,X5R,6.3V,G,SMD0805 | YAGEO CORPORATION COMPONENT | CC0805MKX5R5BB226 |  | G |  |  |  |  |  |  |  |
|  |  |  |  | 7 | 7 | 62011AM00-015-G |  | CAP,6.8nF,+/-10%,X7R,50V,G,SMD0402 | MURATA ELEC. NORTH AMERICA | GRM155R71H682K | 1 | G | C195 |  |  |  |  |  |  |
|  |  |  |  |  | 7 | 62011AM00-012-G |  | CAP,6.8nF,+/-10%,X7R,50V,G,SMD0402 | WALSIN TECHNOLOGY CORPORATION | 0402B682K500CT |  | G |  |  |  |  |  |  |  |
|  |  |  |  |  | 7 | 62011AM00-026-G |  | CAP,6.8nF,+/-10%,X7R,50V,G,SMD0402 | SAMSUNG SEMICONDUCTOR | CL05B682KB5NNNC |  | G |  |  |  |  |  |  |  |
|  |  |  |  | 8 | 8 | 620105E00-015-G |  | CAP,1uF,+/-10%,X7R,10V,G,SMD0603 | MURATA ELEC. NORTH AMERICA | GRM188R71A105K | 2 | G | C197,C215 |  |  |  |  |  |  |
|  |  |  |  |  | 8 | 620105E00-012-G |  | CAP,1uF,+/-10%,X7R,10V,G,SMD0603 | WALSIN TECHNOLOGY CORPORATION | 0603B105K100CT |  | G |  |  |  |  |  |  |  |
|  |  |  |  |  | 8 | 620105E00-011-G |  | CAP,1uF,+/-10%,X7R,10V,G,SMD0603 | YAGEO CORPORATION COMPONENT | CC0603KRX7R6BB105 |  | G |  |  |  |  |  |  |  |
|  |  |  |  |  | 8 | 620105E00-026-G |  | CAP,1uF,+/-10%,X7R,10V,G,SMD0603 | SAMSUNG SEMICONDUCTOR | CL10B105KP8NNNC |  | G |  |  |  |  |  |  |  |
|  |  |  |  |  | 8 | 620105E01-023-G |  | CAP,1uF,+/-10%,X7R,10V,G,SMD0603 | TAIYO ELECTRIC IND.CO.LTD | LMK107B7105KA-T |  | G |  |  |  |  |  |  |  |
|  |  |  |  | 9 | 9 | 620103600-015-G | - | CAP,10nF,+/-10%,X7R,25V,G,SMD0402 | MURATA ELEC. NORTH AMERICA | GRM155R71E103K | 14 | G | C199,C202,C203,C204,C205,C218,C219,C220,C221,C222,C2243,C2244,C2251,C2252 |  |  |  |  |  |  |
|  |  |  |  |  | 9 | 620103600-012-G |  | CAP,10nF,+/-10%,X7R,25V,G,SMD0402 | WALSIN TECHNOLOGY CORPORATION | 0402B103K250CT |  | G |  |  |  |  |  |  |  |
|  |  |  |  |  | 9 | 620103600-011-G |  | CAP,10nF,+/-10%,X7R,25V,G,SMD0402 | YAGEO CORPORATION COMPONENT | CC0402KRX7R8BB103 |  | G |  |  |  |  |  |  |  |
|  |  |  |  |  | 9 | 620103600-026-G |  | CAP,10nF,+/-10%,X7R,25V,G,SMD0402 | SAMSUNG SEMICONDUCTOR | CL05B103KA5NNNC |  | G |  |  |  |  |  |  |  |
|  |  |  |  |  | 9 | 620103601-023-G |  | CAP,10nF,+/-10%,X7R,25V,G,SMD0402 | TAIYO ELECTRIC IND.CO.LTD | TMK105B7103KV-F |  | G |  |  |  |  |  |  |  |
|  |  |  |  | 10 | 10 | 62010L000-015-G | - | CAP,10uF,+/-20%,X5R,6.3V,G,SMD0603 | MURATA ELEC. NORTH AMERICA | GRM188R60J106M | 2 | G | C200,C214 |  |  |  |  |  |  |
|  |  |  |  |  | 10 | 62010L000-023-G |  | CAP,10uF,+/-20%,X5R,6.3V,G,SMD0603 | TAIYO ELECTRIC IND.CO.LTD | JMK107BJ106MA-T |  | G |  |  |  |  |  |  |  |
|  |  |  |  |  | 10 | 62010L000-012-G |  | CAP,10uF,+/-20%,X5R,6.3V,G,SMD0603 | WALSIN TECHNOLOGY CORPORATION | 0603X106M6R3CT |  | G |  |  |  |  |  |  |  |
|  |  |  |  |  | 10 | 62010L000-026-G |  | CAP,10uF,+/-20%,X5R,6.3V,G,SMD0603 | SAMSUNG SEMICONDUCTOR | CL10A106MQ8NNNC |  | G |  |  |  |  |  |  |  |
|  |  |  |  |  | 10 | 62010L000-011-G |  | CAP,10uF,+/-20%,X5R,6.3V,G,SMD0603 | YAGEO CORPORATION COMPONENT | CC0603MRX5R5BB106 |  | G |  |  |  |  |  |  |  |
|  |  |  |  | 11 | 11 | 62011NF01-015-G |  | CAP,2.2uF,+/-10%,X7R,25V,G,SMD0805 | MURATA ELEC. NORTH AMERICA | GRM21BR71E225K | 2 | G | C206,C223 |  |  |  |  |  |  |
|  |  |  |  |  | 11 | 62011NF00-026-G |  | CAP,2.2uF,+/-10%,X7R,25V,G,SMD0805 | SAMSUNG SEMICONDUCTOR | CL21B225KAFNNNE |  | G |  |  |  |  |  |  |  |
|  |  |  |  |  | 11 | 62011NF00-023-G |  | CAP,2.2uF,+/-10%,X7R,25V,G,SMD0805 | TAIYO ELECTRIC IND.CO.LTD | TMK212B7225KG-TR |  | G |  |  |  |  |  |  |  |
|  |  |  |  | 12 | 12 | 620114000-015-G |  | CAP,10uF,+/-10%,X5R,16V,G,SMD0805 | MURATA ELEC. NORTH AMERICA | GRM21BR61C106K | 3 | G | C1946,C2081,C2253 |  |  |  |  |  |  |
|  |  |  |  |  | 12 | 620114005-023-G |  | CAP,10uF,+/-10%,X5R,16V,G,SMD0805 | TAIYO ELECTRIC IND.CO.LTD | EMK212ABJ106KG-T |  | G |  |  |  |  |  |  |  |
|  |  |  |  |  | 12 | 620114000-026-G |  | CAP,10uF,+/-10%,X5R,16V,G,SMD0805 | SAMSUNG SEMICONDUCTOR | CL21A106KOQNNNE |  | G |  |  |  |  |  |  |  |
|  |  |  |  |  | 12 | 620114000-012-G |  | CAP,10uF,+/-10%,X5R,16V,G,SMD0805 | WALSIN TECHNOLOGY CORPORATION | 0805X106K160CT |  | G |  |  |  |  |  |  |  |
|  |  |  |  | 13 | 13 | 620105400-015-G |  | CAP,1uF,+/-10%,X7R,16V,G,SMD0603 | MURATA ELEC. NORTH AMERICA | GRM188R71C105K | 10 | G | C1950,C2080,C2245,C2246,C2247,C2248,C2249,C2250,C2257,C2258 |  |  |  |  |  |  |
|  |  |  |  |  | 13 | 620105400-012-G |  | CAP,1uF,+/-10%,X7R,16V,G,SMD0603 | WALSIN TECHNOLOGY CORPORATION | 0603B105K160CT |  | G |  |  |  |  |  |  |  |
|  |  |  |  |  | 13 | 620105400-011-G |  | CAP,1uF,+/-10%,X7R,16V,G,SMD0603 | YAGEO CORPORATION COMPONENT | CC0603KRX7R7BB105 |  | G |  |  |  |  |  |  |  |
|  |  |  |  |  | 13 | 620105400-026-G |  | CAP,1uF,+/-10%,X7R,16V,G,SMD0603 | SAMSUNG SEMICONDUCTOR | CL10B105KO8NNNC |  | G |  |  |  |  |  |  |  |
|  |  |  |  |  | 13 | 620105400-023-G |  | CAP,1uF,+/-10%,X7R,16V,G,SMD0603 | TAIYO ELECTRIC IND.CO.LTD | EMK107B7105KA-T |  | G |  |  |  |  |  |  |  |
|  |  |  |  | 14 | 14 | 62011LU00-015-G | - | CAP,100nF,+/-10%,X5R,16V,G,SMD0402 | MURATA ELEC. NORTH AMERICA | GRM155R61C104KA88D | 18 | G | C2198,C2208,C2209,C2210,C2211,C2212,C2213,C2214,C2215,C2216,C2217,C2218,C2219,C2220,C2221,C2222,C2223,C2224 |  |  |  |  |  |  |
|  |  |  |  |  | 14 | 620100300-023-G |  | CAP,100nF,+/-10%,X5R,16V,G,SMD0402 | TAIYO | EMK105BJ104KV-F |  | G |  |  |  |  |  |  |  |
|  |  |  |  |  | 14 | 620100300-026-G |  | CAP,100nF,+/-10%,X5R,16V,G,SMD0402 | SAMSUNG SEMICONDUCTOR | CL05A104KO5NNNC |  | G |  |  |  |  |  |  |  |
|  |  |  |  |  | 14 | 620100300-012-G |  | CAP,100nF,+/-10%,X5R,16V,G,SMD0402 | WALSIN TECHNOLOGY CORPORATION | 0402X104K160CT |  | G |  |  |  |  |  |  |  |
|  |  |  |  | 15 | 15 | 620109S00-023-G |  | CAP,4.7uF,+/-10%,X7R,10V,G,SMD0805 | TAIYO ELECTRIC IND.CO.LTD | LMK212B7475KG-T | 1 | G | C2231 |  |  |  |  |  |  |
|  |  |  |  |  | 15 | 620109S00-026-G |  | CAP,4.7uF,+/-10%,X7R,10V,G,SMD0805 | SAMSUNG SEMICONDUCTOR | CL21B475KPFNNNE |  | G |  |  |  |  |  |  |  |
|  |  |  |  |  | 15 | 620109S00-015-G |  | CAP,4.7uF,+/-10%,X7R,10V,G,SMD0805 | MURATA ELEC. NORTH AMERICA | GRM21BR71A475K |  | G |  |  |  |  |  |  |  |
|  |  |  |  | 16 | 16 | 62012UW00-015-G | - | CAP,6.8pF,+/-0.05pF,NPO(C0G),25V,G,SMD0402 | MURATA ELEC. NORTH AMERICA | GRM1555C1E6R8WA01D | 2 | G | C2268,C2269 |  |  |  |  |  |  |
|  |  |  |  |  | 16 | 62012UW00-012-G |  | CAP,6.8pF,+/-0.05pF,NPO(C0G),25V,G,SMD0402 | WALSIN TECHNOLOGY CORPORATION | 0402N6R8A250CT |  | G |  |  |  |  |  |  |  |
|  |  |  |  | 17 | 17 | 52110LN00-289-G |  | LED,Gre,LTST-C191KGKT,2.4V,30mA,G,SMD0603 | LITE-ON TECHNOLOGY CORPORATION | LTST-C191KGKT | 24 | G | LED37,LED39,LED49,LED51,LED53,LED55,LED57,LED59,LED61,LED63,LED65,LED67,LED69,LED71,LED73,LED75,LED77,LED79,LED81,LED83,LED85,LED87,LED89,LED91 |  |  |  |  |  |  |
|  |  |  |  | 18 | 18 | 52110A800-289-G | 6W731 | LED,Gre/Yel,LTST-C195KGJSKT,2.4V,30mA,G,SMD | LITE-ON TECHNOLOGY CORPORATION | LTST-C195KGJSKT | 24 | G | LED38,LED40,LED50,LED52,LED54,LED56,LED58,LED60,LED62,LED64,LED66,LED68,LED70,LED72,LED74,LED76,LED78,LED80,LED82,LED84,LED86,LED88,LED90,LED92 |  |  |  |  |  |  |
|  |  |  |  | 19 | 19 | 720101900-015-G | - | FB,60 Ohm@100MHz,+/-25%,3A,25mOhm,G,SMD0805 | MURATA ELEC. NORTH AMERICA | BLM21PG600SN1D | 1 | G | L1 |  |  |  |  |  |  |
|  |  |  |  | 20 | 20 | 72010JY00-015-G |  | FB,330 Ohm@100MHz,+/-25%,1.5A,70mOhm,G,SMD0603 | MURATA ELEC. NORTH AMERICA | BLM18SG331TN1D | 2 | G | L2,L4 |  |  |  |  |  |  |
|  |  |  |  | 21 | 21 | 72010FB01-016-G |  | FB,600 Ohm@100MHz,+/-25%,1A,150mOhm,G,SMD0603 | TDK ELECTRONICS EUROPE GMBH | MPZ1608S601AT | 2 | G | L6,L28 |  |  |  |  |  |  |
|  |  |  |  | 22 | 22 | 720102001-015-G | - | FB,30 Ohm@100MHz,+/-25%,3A,15mOhm,G,SMD0805 | MURATA ELEC. NORTH AMERICA | BLM21PG300SN1D | 1 | G | L30 |  |  |  |  |  |  |
|  |  |  |  | 23 | 23 | 720101L00-015-G | R8955 | FB,600 Ohm@100MHz,+/-25%,200mA,500mOhm,G,SMD0603 | MURATA ELEC. NORTH AMERICA | BLM18AG601SN1D | 1 | G | L31 |  |  |  |  |  |  |
|  |  |  |  | 24 | 24 | 71020NS00-967-G |  | OSC,25MHz,+/-25ppm,3.3V,15pF,G,SMD | SaRonix-eCERA Corporation | FK2500025 | 2 | G | OSC1,OSC2 |  |  |  |  |  |  |
|  |  |  |  | 25 | 25 | 62120HT00-024-G |  | ECAP,SPEA,100uF,+/-20%,10V,105C,G,SMD2816,ESR<=40mOhm | PANASONIC INDUSTRIAL CO.,LTD. | EEFCX1A101R | 3 | G | PSTCE3003,PFTCE3003,PETCE3003 |  |  |  |  |  |  |
|  |  |  |  | 26 | 26 | 62012PT00-015-G |  | CAP,22uF,+/-20%,X6S,16V,G,SMD0805 | MURATA ELEC. NORTH AMERICA | GRM21BC81C226M | 14 | G | PSTC2,PFTC2,PETC2,PSTC3,PFTC3,PETC3,PSRC7,PSRC8,PSRC11,PSRC12,PSRC15,PSTC3000,PFTC3000,PETC3000 |  |  |  |  |  |  |
|  |  |  |  |  | 26 | 62012PT00-023-G |  | CAP,22uF,+/-20%,X6S,16V,G,SMD0805 | TAIYO ELECTRIC IND.CO.LTD | EDK212BC6226MG-T |  | G |  |  |  |  |  |  |  |
|  |  |  |  | 27 | 27 | 620108000-015-G | - | CAP,100pF,+/-5%,NPO(C0G),50V,G,SMD0402 | MURATA ELEC. NORTH AMERICA | GRM1555C1H101J | 3 | G | PSTC4,PFTC4,PETC4 |  |  |  |  |  |  |
|  |  |  |  |  | 27 | 62010800A-012-G |  | CAP,100pF,+/-5%,NPO(C0G),50V,G,SMD0402 | WALSIN TECHNOLOGY CORPORATION | 0402N101J500CT |  | G |  |  |  |  |  |  |  |
|  |  |  |  |  | 27 | 620108000-026-G |  | CAP,100pF,+/-5%,NPO(C0G),50V,G,SMD0402 | SAMSUNG SEMICONDUCTOR | CL05C101JB5NNNC |  | G |  |  |  |  |  |  |  |
|  |  |  |  |  | 27 | 620108000-023-G |  | CAP,100pF,+/-5%,NPO(C0G),50V,G,SMD0402 | TAIYO ELECTRIC IND.CO.LTD | UMK105CG101JV-F |  | G |  |  |  |  |  |  |  |
|  |  |  |  | 28 | 28 | 62010L800-015-G | - | CAP,1nF,+/-5%,NPO(C0G),50V,G,SMD0402 | MURATA ELEC. NORTH AMERICA | GRM1555C1H102J | 3 | G | PSTC5,PFTC5,PETC5 |  |  |  |  |  |  |
|  |  |  |  |  | 28 | 62010L800-012-G |  | CAP,1nF,+/-5%,NPO(C0G),50V,G,SMD0402 | WALSIN TECHNOLOGY CORPORATION | 0402N102J500CT |  | G |  |  |  |  |  |  |  |
|  |  |  |  |  | 28 | 62010L800-026-G |  | CAP,1nF,+/-5%,NPO(C0G),50V,G,SMD0402 | SAMSUNG SEMICONDUCTOR | CL05C102JB5NNNC |  | G |  |  |  |  |  |  |  |
|  |  |  |  | 29 | 29 | 62012T500-015-G |  | CAP,22uF,+/-20%,X7S,25V,G,SMD1206 | MURATA ELEC. NORTH AMERICA | GRM31CC71E226ME11L | 41 | G | PSRC2,PSTC6,PFTC6,PETC6,PSTC7,PFTC7,PETC7,PSTC8,PFTC8,PETC8,PSTC9,PFTC9,PETC9,PSRC17,PSTC3005,PFTC3005,PETC3005,PSTC3006,PFTC3006,PETC3006,PSTC3007,PFTC3007,PETC3007,PSTC3010,PFTC3010,PETC3010,PSTC3011,PFTC3011,PETC3011,PSTC3012,PFTC3012,PETC3012,PSTC3013,PFTC3013,PETC3013,PFTC3014,PETC3014,PFTC3015,PETC3015,PFTC3016,PETC3016 |  |  |  |  |  |  |
|  |  |  |  | 30 | 30 | 620103U00-015-G | - | CAP,470pF,+/-10%,X7R,50V,G,SMD0402 | MURATA ELEC. NORTH AMERICA | GRM155R71H471K | 3 | G | PSTC10,PFTC10,PETC10 |  |  |  |  |  |  |
|  |  |  |  |  | 30 | 620103U00-012-G |  | CAP,470pF,+/-10%,X7R,50V,G,SMD0402 | WALSIN TECHNOLOGY CORPORATION | 0402B471K500CT |  | G |  |  |  |  |  |  |  |
|  |  |  |  |  | 30 | 620103U00-026-G |  | CAP,470pF,+/-10%,X7R,50V,G,SMD0402 | SAMSUNG SEMICONDUCTOR | CL05B471KB5NNNC |  | G |  |  |  |  |  |  |  |
|  |  |  |  |  | 30 | 620103U00-023-G |  | CAP,470pF,+/-10%,X7R,50V,G,SMD0402 | TAIYO ELECTRIC IND.CO.LTD | UMK105B7471KV-F |  | G |  |  |  |  |  |  |  |
|  |  |  |  | 31 | 31 | 62010FG00-015-G | - | CAP,3.3pF,+/-0.25pF,NPO(C0G),50V,G,SMD0402 | MURATA ELEC. NORTH AMERICA | GRM1555C1H3R3C | 3 | G | PSTC11,PFTC11,PETC11 |  |  |  |  |  |  |
|  |  |  |  |  | 31 | 62010FG08-012-G |  | CAP,3.3pF,+/-0.25pF,NPO(C0G),50V,G,SMD0402 | WALSIN TECHNOLOGY CORPORATION | 0402N3R3C500CT |  | G |  |  |  |  |  |  |  |
|  |  |  |  |  | 31 | 62010FG00-026-G |  | CAP,3.3pF,+/-0.25pF,NPO(C0G),50V,G,SMD0402 | SAMSUNG SEMICONDUCTOR | CL05C3R3CB5ANNC |  | G |  |  |  |  |  |  |  |
|  |  |  |  | 32 | 32 | 620107L00-015-G | - | CAP,2.2nF,+/-10%,X7R,50V,G,SMD0402 | MURATA ELEC. NORTH AMERICA | GRM155R71H222K | 3 | G | PSTC12,PFTC12,PETC12 |  |  |  |  |  |  |
|  |  |  |  |  | 32 | 620107L00-012-G |  | CAP,2.2nF,+/-10%,X7R,50V,G,SMD0402 | WALSIN TECHNOLOGY CORPORATION | 0402B222K500CT |  | G |  |  |  |  |  |  |  |
|  |  |  |  |  | 32 | 620107L00-026-G |  | CAP,2.2nF,+/-10%,X7R,50V,G,SMD0402 | SAMSUNG SEMICONDUCTOR | CL05B222KB5NNNC |  | G |  |  |  |  |  |  |  |
|  |  |  |  |  | 32 | 620107L03-023-G |  | CAP,2.2nF,+/-10%,X7R,50V,G,SMD0402 | TAIYO ELECTRIC IND.CO.LTD | UMK105B7222KV-F |  | G |  |  |  |  |  |  |  |
|  |  |  |  | 33 | 33 | 62012A400-015-G | - | CAP,100nF,+/-10%,X7R,25V,G,SMD0402 | MURATA ELEC. NORTH AMERICA | GRM155R71E104KE14D | 8 | G | PSRC1,PSRC6,PSTC3002,PFTC3002,PETC3002,PSTC3008,PFTC3008,PETC3008 |  |  |  |  |  |  |
|  |  |  |  |  | 33 | 62012A400-023-G |  | CAP,100nF,+/-10%,X7R,25V,G,SMD0402 | TAIYO ELECTRIC IND.CO.LTD | TMK105B7104KV-FR |  | G |  |  |  |  |  |  |  |
|  |  |  |  |  | 33 | 62012A400-026-G |  | CAP,100nF,+/-10%,X7R,25V,G,SMD0402 | SAMSUNG SEMICONDUCTOR | CL05B104KA5NNNC |  | G |  |  |  |  |  |  |  |
|  |  |  |  |  | 33 | 62012A400-012-G |  | CAP,100nF,+/-10%,X7R,25V,G,SMD0402 | WALSIN TECHNOLOGY CORPORATION | 0402B104K250CT |  | G |  |  |  |  |  |  |  |
|  |  |  |  | 34 | 34 | 62012T300-015-G |  | CAP,1uF,+/-10%,X7S,25V,G,SMD0402 | MURATA ELEC. NORTH AMERICA | GRM155C71E105KE11D | 4 | G | PSRC4,PSTC3003,PFTC3003,PETC3003 |  |  |  |  |  |  |
|  |  |  |  |  | 34 | 620138700-026-G |  | CAP,1uF,+/-10%,X6S,25V,G,SMD0402 | SAMSUNG SEMICONDUCTOR | CL05X105KA5NQNC |  | G |  |  |  |  |  |  |  |
|  |  |  |  |  | 34 | 620138700-015-G |  | CAP,1uF,+/-10%,X6S,25V,G,SMD0402 | MURATA | GRM155C81E105KE11D |  | G |  |  |  |  |  |  |  |
|  |  |  |  | 35 | 35 | 62012GG00-015-G |  | CAP,10uF,+/-10%,X7S,25V,G,SMD0805 | MURATA ELEC. NORTH AMERICA | GRM21BC71E106K | 7 | G | PSRC3,PSTC3004,PFTC3004,PETC3004,PSTC3009,PFTC3009,PETC3009 |  |  |  |  |  |  |
|  |  |  |  |  | 35 | 62012GG00-012-G |  | CAP,10uF,+/-10%,X7S,25V,G,SMD0805 | WALSIN TECHNOLOGY CORPORATION | 0805A106K250CT |  | G |  |  |  |  |  |  |  |
|  |  |  |  | 36 | 36 | 630335M00-088-G |  | IND,820nH@100KHz,+/-20%,13A,8mOhm,SHLD,G,SMD | COOPER BUSSMANN, INC. | HCM0703-R82-R | 3 | G | PSTL1,PFTL1,PETL1 |  |  |  |  |  |  |
|  |  |  |  | 37 | 37 | 630341400-088-G |  | IND,22nH@1MHz,+/-20%,19A,368uOhm,SHLD,G,SMD | COOPER BUSSMANN, INC. | FP0404R1-R022-R | 3 | G | PSTL2,PFTL2,PETL2 |  |  |  |  |  |  |
|  |  |  |  | 38 | 38 | 61010LA00-017-G | - | RES,4.7KOhm,+/-1%,1/16W,G,SMD0402 | KOA SPEER ELECTRONICS, INC. | RK73H1ETTP4701F | 45 | G | PSTR1,PFTR1,PETR1,R336,R1605,R1700,R1701,R1702,R1703,R1704,R1705,R1706,R1707,R1708,R1709,R1710,R1711,R1712,R1713,R1714,R1715,R1716,R1717,R1718,R1719,R1720,R1721,R1722,R1723,R1724,R1725,R1726,R1727,R1728,R1729,R1730,R1731,R1732,R1733,R1734,R1735,R1736,R1737,R1738,R1739 |  |  |  |  |  |  |
|  |  |  |  |  | 38 | 61010LA00-012-G |  | RES,4.7KOhm,+/-1%,1/16W,G,SMD0402 | WALSIN TECHNOLOGY CORPORATION | WR04X4701FTL |  | G |  |  |  |  |  |  |  |
|  |  |  |  |  | 38 | 61010LA00-011-G |  | RES,4.7KOhm,+/-1%,1/16W,G,SMD0402 | YAGEO CORPORATION COMPONENT | RC0402FR-074K7L |  | G |  |  |  |  |  |  |  |
|  |  |  |  |  | 38 | 61010LA00-044-G |  | RES,4.7KOhm,+/-1%,1/16W,G,SMD0402 | TA-I TECHNOLOGY CO., LTD | RM04FTN4701 |  | G |  |  |  |  |  |  |  |
|  |  |  |  | 39 | 39 | 610107A00-017-G | - | RES,0 Ohm,+/-5%,1/16W,G,SMD0402 | KOA SPEER ELECTRONICS, INC. | RK73Z1ETTP | 146 | G | PSTR2,PFTR2,PETR2,R5,PSTR7,PFTR7,PETR7,R8,PSTR8,PSRR8,PFTR8,PETR8,PSRR9,R10,PSTR14,PFTR14,PETR14,PSRR15,PSRR18,PSTR22,PSRR22,PFTR22,PETR22,R60,R65,R511,R568,R569,R570,R571,R1888,R1889,R1890,R1891,R1892,R1893,R1894,R1895,R1896,R1897,R1898,R1899,R1900,R1901,R1902,R1903,R1988,R1989,R1990,R1991,R1992,R1993,R1994,R1995,R1996,R1997,R1998,R1999,R2000,R2001,R2002,R2003,R2004,R2005,R2006,R2007,R2008,R2009,R2010,R2011,R2012,R2013,R2014,R2015,R2016,R2017,R2018,R2019,R2020,R2021,R2022,R2023,R2024,R2025,R2026,R2027,R2028,R2029,R2030,R2031,R2032,R2033,R2034,R2035,R2036,R2037,R2038,R2039,R2040,R2041,R2042,R2043,R2044,R2045,R2046,R2047,R2061,R2066,R2067,R2070,R2085,R2086,R2152,R2153,R2154,R2155,R2158,R2180,R2181,R2182,R2183,R2184,R2185,R2186,R2187,R2188,R2189,R2190,R2191,R2192,R2193,R2194,R2195,R2196,R2197,R2198,R2199,PSTR3001,PFTR3001,PETR3001,PSTR3002,PFTR3002,PETR3002,PSTR3003,PFTR3003,PETR3003 |  |  |  |  |  |  |
|  |  |  |  |  | 39 | 610107A00-012-G |  | RES,0 Ohm,+/-5%,1/16W,G,SMD0402 | WALSIN TECHNOLOGY CORPORATION | WR04X000PTL |  | G |  |  |  |  |  |  |  |
|  |  |  |  |  | 39 | 610107A00-011-G |  | RES,0 Ohm,+/-5%,1/16W,G,SMD0402 | YAGEO CORPORATION COMPONENT | RC0402JR-070RL |  | G |  |  |  |  |  |  |  |
|  |  |  |  |  | 39 | 610107A00-044-G |  | RES,0 Ohm,+/-5%,1/16W,G,SMD0402 | TA-I TECHNOLOGY CO., LTD | RM04JTN0 |  | G |  |  |  |  |  |  |  |
|  |  |  |  |  | 39 | 610107A00-024-G |  | RES,0 Ohm,+/-5%,1/16W,G,SMD0402 | PANASONIC INDUSTRIAL CO.,LTD. | ERJ2GE0R00X |  | G |  |  |  |  |  |  |  |
|  |  |  |  |  | 39 | 610107A00-029-G |  | RES,0 Ohm,+/-5%,1/16W,G,SMD0402 | VISHAY ENTER TECHNO LOGY.INC | CRCW04020000Z0ED |  | G |  |  |  |  |  |  |  |
|  |  |  |  | 40 | 40 | 61011HA00-017-G |  | RES,1 Ohm,+/-1%,1/16W,G,SMD0402 | KOA SPEER ELECTRONICS, INC. | RK73H1ETTP1R00F | 4 | G | PSTR4,PFTR4,PETR4,PSRR5 |  |  |  |  |  |  |
|  |  |  |  |  | 40 | 61011HA00-012-G |  | RES,1 Ohm,+/-1%,1/16W,G,SMD0402 | WALSIN TECHNOLOGY CORPORATION | WR04W1R00FTL |  | G |  |  |  |  |  |  |  |
|  |  |  |  |  | 40 | 61011HA00-011-G |  | RES,1 Ohm,+/-1%,1/16W,G,SMD0402 | YAGEO CORPORATION COMPONENT | RC0402FR-071RL |  | G |  |  |  |  |  |  |  |
|  |  |  |  |  | 40 | 61011HA00-044-G |  | RES,1 Ohm,+/-1%,1/16W,G,SMD0402 | TA-I TECHNOLOGY CO., LTD | RM04FTN1R00 |  | G |  |  |  |  |  |  |  |
|  |  |  |  |  | 40 | 61011HA00-029-G |  | RES,1 Ohm,+/-1%,1/16W,G,SMD0402 | VISHAY ENTER TECHNO LOGY.INC | CRCW04021R00FNED |  | G |  |  |  |  |  |  |  |
|  |  |  |  | 41 | 41 | 61100QD00-017-G |  | RES,787 Ohm,+/-0.1%,1/16W,G,SMD0402 | KOA SPEER ELECTRONICS, INC. | RN731ETTP7870B25 | 3 | G | PSTR5,PFTR5,PETR5 |  |  |  |  |  |  |
|  |  |  |  | 42 | 42 | 61100SU00-017-G |  | RES,105 Ohm,+/-0.1%,1/16W,G,SMD0402 | KOA SPEER ELECTRONICS, INC. | RN731ETTP1050B25 | 3 | G | PSTR6,PFTR6,PETR6 |  |  |  |  |  |  |
|  |  |  |  | 43 | 43 | 61011BD00-017-G |  | RES,46.4KOhm,+/-1%,1/16W,G,SMD0402 | KOA SPEER ELECTRONICS, INC. | RK73H1ETTP4642F | 3 | G | PSTR9,PFTR9,PETR9 |  |  |  |  |  |  |
|  |  |  |  |  | 43 | 61011BD00-011-G |  | RES,46.4KOhm,+/-1%,1/16W,G,SMD0402 | YAGEO CORPORATION COMPONENT | RC0402FR-0746K4L |  | G |  |  |  |  |  |  |  |
|  |  |  |  |  | 43 | 61011BD00-012-G |  | RES,46.4KOhm,+/-1%,1/16W,G,SMD0402 | WALSIN TECHNOLOGY CORPORATION | WR04X4642FTL |  | G |  |  |  |  |  |  |  |
|  |  |  |  |  | 43 | 61011BD00-044-G |  | RES,46.4KOhm,+/-1%,1/16W,G,SMD0402 | TA-I TECHNOLOGY CO., LTD | RM04FTN4642 |  | G |  |  |  |  |  |  |  |
|  |  |  |  | 44 | 44 | 610124U00-017-G | - | RES,7.87KOhm,+/-1%,1/16W,G,SMD0402 | KOA SPEER ELECTRONICS, INC. | RK73H1ETTP7871F | 3 | G | PSTR10,PFTR10,PETR10 |  |  |  |  |  |  |
|  |  |  |  |  | 44 | 610124U00-012-G |  | RES,7.87KOhm,+/-1%,1/16W,G,SMD0402 | WALSIN TECHNOLOGY CORPORATION | WR04X7871FTL |  | G |  |  |  |  |  |  |  |
|  |  |  |  |  | 44 | 610124U00-011-G |  | RES,7.87KOhm,+/-1%,1/16W,G,SMD0402 | YAGEO CORPORATION COMPONENT | RC0402FR-077K87L |  | G |  |  |  |  |  |  |  |
|  |  |  |  |  | 44 | 610124U00-044-G |  | RES,7.87KOhm,+/-1%,1/16W,G,SMD0402 | TA-I TECHNOLOGY CO., LTD | RM04FTN7871 |  | G |  |  |  |  |  |  |  |
|  |  |  |  | 45 | 45 | 610112J00-017-G | - | RES,200 Ohm,+/-1%,1/16W,G,SMD0402 | KOA SPEER ELECTRONICS, INC. | RK73H1ETTP2000F | 3 | G | PSTR11,PFTR11,PETR11 |  |  |  |  |  |  |
|  |  |  |  |  | 45 | 610112J00-012-G |  | RES,200 Ohm,+/-1%,1/16W,G,SMD0402 | WALSIN TECHNOLOGY CORPORATION | WR04X2000FTL |  | G |  |  |  |  |  |  |  |
|  |  |  |  |  | 45 | 610112J00-011-G |  | RES,200 Ohm,+/-1%,1/16W,G,SMD0402 | YAGEO CORPORATION COMPONENT | RC0402FR-07200RL |  | G |  |  |  |  |  |  |  |
|  |  |  |  |  | 45 | 610112J00-044-G |  | RES,200 Ohm,+/-1%,1/16W,G,SMD0402 | TA-I TECHNOLOGY CO., LTD | RM04FTN2000 |  | G |  |  |  |  |  |  |  |
|  |  |  |  |  | 45 | 610112J00-029-G |  | RES,200 Ohm,+/-1%,1/16W,G,SMD0402 | VISHAY ENTER TECHNO LOGY.INC | CRCW0402200RFKED |  | G |  |  |  |  |  |  |  |
|  |  |  |  |  | 45 | 610112J00-024-G |  | RES,200 Ohm,+/-1%,1/16W,G,SMD0402 | PANASONIC INDUSTRIAL CO.,LTD. | ERJ2RKF2000X |  | G |  |  |  |  |  |  |  |
|  |  |  |  | 46 | 46 | 61011JY00-017-G | - | RES,39.2KOhm,+/-1%,1/16W,G,SMD0402 | KOA SPEER ELECTRONICS, INC. | RK73H1ETTP3922F | 3 | G | PSTR15,PFTR15,PETR15 |  |  |  |  |  |  |
|  |  |  |  |  | 46 | 61011JY00-012-G |  | RES,39.2KOhm,+/-1%,1/16W,G,SMD0402 | WALSIN TECHNOLOGY CORPORATION | WR04X3922FTL |  | G |  |  |  |  |  |  |  |
|  |  |  |  |  | 46 | 61011JY00-011-G |  | RES,39.2KOhm,+/-1%,1/16W,G,SMD0402 | YAGEO CORPORATION COMPONENT | RC0402FR-0739K2L |  | G |  |  |  |  |  |  |  |
|  |  |  |  |  | 46 | 61011JY00-044-G |  | RES,39.2KOhm,+/-1%,1/16W,G,SMD0402 | TA-I TECHNOLOGY CO., LTD | RM04FTN3922 |  | G |  |  |  |  |  |  |  |
|  |  |  |  |  | 46 | 61011JY00-029-G |  | RES,39.2KOhm,+/-1%,1/16W,G,SMD0402 | VISHAY ENTER TECHNO LOGY.INC | CRCW040239K2FKED |  | G |  |  |  |  |  |  |  |
|  |  |  |  | 47 | 47 | 32013P700-238-G |  | IC,Regulator,IR3448MTRPBF,ADJ,16A,G,PQFN-33,SMD | INTERNATIONAL RECTIFIER | IR3448MTRPBF | 3 | G | PSTU1,PFTU1,PETU1 |  |  |  |  |  |  |
|  |  |  |  | 48 | 48 | 62012P100-015-G |  | CAP,2.2uF,+/-20%,X7S,10V,G,SMD0402 | MURATA ELEC. NORTH AMERICA | GRM155C71A225M | 1 | G | PSRC5 |  |  |  |  |  |  |
|  |  |  |  |  | 48 | 62012P100-012-G |  | CAP,2.2uF,+/-20%,X7S,10V,G,SMD0402 | WALSIN TECHNOLOGY CORPORATION | 0402A225M100CT |  | G |  |  |  |  |  |  |  |
|  |  |  |  | 49 | 49 | 620105U00-015-G | - | CAP,220pF,+/-10%,X7R,50V,G,SMD0402 | MURATA ELEC. NORTH AMERICA | GRM155R71H221K | 1 | G | PSRC14 |  |  |  |  |  |  |
|  |  |  |  |  | 49 | 620105U00-012-G |  | CAP,220pF,+/-10%,X7R,50V,G,SMD0402 | WALSIN TECHNOLOGY CORPORATION | 0402B221K500CT |  | G |  |  |  |  |  |  |  |
|  |  |  |  |  | 49 | 620105U00-026-G |  | CAP,220pF,+/-10%,X7R,50V,G,SMD0402 | SAMSUNG SEMICONDUCTOR | CL05B221KB5NNNC |  | G |  |  |  |  |  |  |  |
|  |  |  |  | 50 | 50 | 62012H100-015-G |  | CAP,10uF,+/-20%,X6S,10V,G,SMD0603 | MURATA ELEC. NORTH AMERICA | GRM188C81A106M | 1 | G | PSRC16 |  |  |  |  |  |  |
|  |  |  |  |  | 50 | 62012H100-023-G |  | CAP,10uF,+/-20%,X6S,10V,G,SMD0603 | TAIYO ELECTRIC IND.CO.LTD | LMK107BC6106MA-T |  | G |  |  |  |  |  |  |  |
|  |  |  |  |  | 50 | 62012H100-026-G |  | CAP,10uF,+/-20%,X6S,10V,G,SMD0603 | SAMSUNG SEMICONDUCTOR | CL10X106MP8NRNC |  | G |  |  |  |  |  |  |  |
|  |  |  |  | 51 | 51 | 72010RE00-015-G |  | FB,26 Ohm@100MHz,+/-25%,6A,7mOhm,G,SMD0603 | MURATA ELEC. NORTH AMERICA | BLM18KG260TN1D | 1 | G | PSRL1 |  |  |  |  |  |  |
|  |  |  |  | 52 | 52 | 63032PP00-088-G |  | IND,4.7uH@100KHz,+/-20%,5.5A,40mOhm,SHLD,G,SMD | COOPER BUSSMANN, INC. | HCM0703-4R7-R | 1 | G | PSRL2 |  |  |  |  |  |  |
|  |  |  |  | 53 | 53 | 610117D00-017-G | - | RES,13.3KOhm,+/-1%,1/16W,G,SMD0402 | KOA SPEER ELECTRONICS, INC. | RK73H1ETTP1332F | 1 | G | PSRR1 |  |  |  |  |  |  |
|  |  |  |  |  | 53 | 610117D00-012-G |  | RES,13.3KOhm,+/-1%,1/16W,G,SMD0402 | WALSIN TECHNOLOGY CORPORATION | WR04X1332FTL |  | G |  |  |  |  |  |  |  |
|  |  |  |  |  | 53 | 610117D00-011-G |  | RES,13.3KOhm,+/-1%,1/16W,G,SMD0402 | YAGEO CORPORATION COMPONENT | RC0402FR-0713K3L |  | G |  |  |  |  |  |  |  |
|  |  |  |  |  | 53 | 610117D00-044-G |  | RES,13.3KOhm,+/-1%,1/16W,G,SMD0402 | TA-I TECHNOLOGY CO., LTD | RM04FTN1332 |  | G |  |  |  |  |  |  |  |
|  |  |  |  | 54 | 54 | 610114S00-017-G | - | RES,4.99KOhm,+/-1%,1/16W,G,SMD0402 | KOA SPEER ELECTRONICS, INC. | RK73H1ETTP4991F | 1 | G | PSRR3 |  |  |  |  |  |  |
|  |  |  |  |  | 54 | 610114S00-012-G |  | RES,4.99KOhm,+/-1%,1/16W,G,SMD0402 | WALSIN TECHNOLOGY CORPORATION | WR04X4991FTL |  | G |  |  |  |  |  |  |  |
|  |  |  |  |  | 54 | 610114S00-011-G |  | RES,4.99KOhm,+/-1%,1/16W,G,SMD0402 | YAGEO CORPORATION COMPONENT | RC0402FR-074K99L |  | G |  |  |  |  |  |  |  |
|  |  |  |  |  | 54 | 610114S00-044-G |  | RES,4.99KOhm,+/-1%,1/16W,G,SMD0402 | TA-I TECHNOLOGY CO., LTD | RM04FTN4991 |  | G |  |  |  |  |  |  |  |
|  |  |  |  |  | 54 | 610114S00-024-G |  | RES,4.99KOhm,+/-1%,1/16W,G,SMD0402 | PANASONIC INDUSTRIAL CO.,LTD. | ERJ2RKF4991X |  | G |  |  |  |  |  |  |  |
|  |  |  |  | 55 | 55 | 61010G500-017-G | - | RES,10KOhm,+/-1%,1/16W,G,SMD0402 | KOA SPEER ELECTRONICS, INC. | RK73H1ETTP1002F | 1 | G | PSRR6 |  |  |  |  |  |  |
|  |  |  |  |  | 55 | 61010G500-012-G |  | RES,10KOhm,+/-1%,1/16W,G,SMD0402 | WALSIN TECHNOLOGY CORPORATION | WR04X1002FTL |  | G |  |  |  |  |  |  |  |
|  |  |  |  |  | 55 | 61010G500-011-G |  | RES,10KOhm,+/-1%,1/16W,G,SMD0402 | YAGEO CORPORATION COMPONENT | RC0402FR-0710KL |  | G |  |  |  |  |  |  |  |
|  |  |  |  |  | 55 | 61010G500-044-G |  | RES,10KOhm,+/-1%,1/16W,G,SMD0402 | TA-I TECHNOLOGY CO., LTD | RM04FTN1002 |  | G |  |  |  |  |  |  |  |
|  |  |  |  |  | 55 | 61010G500-029-G |  | RES,10KOhm,+/-1%,1/16W,G,SMD0402 | VISHAY ENTER TECHNO LOGY.INC | CRCW040210K0FKED |  | G |  |  |  |  |  |  |  |
|  |  |  |  |  | 55 | 61010G500-024-G |  | RES,10KOhm,+/-1%,1/16W,G,SMD0402 | PANASONIC INDUSTRIAL CO.,LTD. | ERJ2RKF1002X |  | G |  |  |  |  |  |  |  |
|  |  |  |  | 56 | 56 | 611004M00-017-G |  | RES,16.5KOhm,+/-0.1%,1/16W,G,SMD0402 | KOA SPEER ELECTRONICS, INC. | RN731ETTP1652B25 | 1 | G | PSRR17 |  |  |  |  |  |  |
|  |  |  |  | 57 | 57 | 61100YB00-017-G |  | RES,2.94KOhm,+/-0.1%,1/16W,G,SMD0402 | KOA SPEER ELECTRONICS, INC. | RN731ETTP2941B25 | 1 | G | PSRR19 |  |  |  |  |  |  |
|  |  |  |  | 58 | 58 | 32013PD00-238-G |  | IC,Regulator,IR3883MTRPbF,ADJ,3A,G,QFN-16,SMD | INTERNATIONAL RECTIFIER | IR3883MTRPBF | 1 | G | PSRU1 |  |  |  |  |  |  |
|  |  |  |  | 59 | 59 | 510504M00-237-G |  | MOS N/N,BSS138DW-7-F,50V,0.2A,3.5ohm@10V,G,SOT363-6,SMD | DIODES INEORPORATION | BSS138DW-7-F | 25 | G | QN19,QN20,QN25,QN26,QN27,QN28,QN29,QN30,QN31,QN33,QN34,QN35,QN36,QN37,QN38,QN39,QN40,QN41,QN42,QN43,QN44,QN45,QN46,QN47,QN48 |  |  |  |  |  |  |
|  |  |  |  | 60 | 60 | 61011H500-017-G | - | RES,22 Ohm,+/-1%,1/16W,G,SMD0402 | KOA SPEER ELECTRONICS, INC. | RK73H1ETTP22R0F | 12 | G | R1,R14,R338,R504,R509,R531,R550,R552,R572,R868,R869,R2148 |  |  |  |  |  |  |
|  |  |  |  |  | 60 | 61011H500-012-G |  | RES,22 Ohm,+/-1%,1/16W,G,SMD0402 | WALSIN TECHNOLOGY CORPORATION | WR04X22R0FTL |  | G |  |  |  |  |  |  |  |
|  |  |  |  |  | 60 | 61011H500-011-G |  | RES,22 Ohm,+/-1%,1/16W,G,SMD0402 | YAGEO CORPORATION COMPONENT | RC0402FR-0722RL |  | G |  |  |  |  |  |  |  |
|  |  |  |  |  | 60 | 61011H500-044-G |  | RES,22 Ohm,+/-1%,1/16W,G,SMD0402 | TA-I TECHNOLOGY CO., LTD | RM04FTN22R0 |  | G |  |  |  |  |  |  |  |
|  |  |  |  |  | 60 | 61011H500-024-G |  | RES,22 Ohm,+/-1%,1/16W,G,SMD0402 | PANASONIC INDUSTRIAL CO.,LTD. | ERJ2RKF22R0X |  | G |  |  |  |  |  |  |  |
|  |  |  |  | 61 | 61 | 61011MQ00-017-G | - | RES,4.75KOhm,+/-1%,1/16W,G,SMD0402 | KOA SPEER ELECTRONICS, INC. | RK73H1ETTP4751F | 2 | G | R2,R4 |  |  |  |  |  |  |
|  |  |  |  |  | 61 | 61011MQ00-011-G |  | RES,4.75KOhm,+/-1%,1/16W,G,SMD0402 | YAGEO CORPORATION COMPONENT | RC0402FR-074K75L |  | G |  |  |  |  |  |  |  |
|  |  |  |  |  | 61 | 61011MQ00-012-G |  | RES,4.75KOhm,+/-1%,1/16W,G,SMD0402 | WALSIN TECHNOLOGY CORPORATION | WR04X4751FTL |  | G |  |  |  |  |  |  |  |
|  |  |  |  |  | 61 | 61011MQ00-044-G |  | RES,4.75KOhm,+/-1%,1/16W,G,SMD0402 | TA-I TECHNOLOGY CO., LTD | RM04FTN4751 |  | G |  |  |  |  |  |  |  |
|  |  |  |  | 62 | 62 | 610107B00-017-G | K9576 | RES,4.7KOhm,+/-5%,1/16W,G,SMD0402 | KOA SPEER ELECTRONICS, INC. | RK73B1ETTP472J | 134 | G | R6,R7,R9,R16,R17,R18,R62,R228,R312,R323,R324,R331,R333,R337,R411,R413,R417,R427,R429,R433,R443,R445,R448,R460,R461,R465,R475,R477,R480,R492,R493,R497,R503,R505,R506,R507,R510,R512,R513,R514,R516,R527,R528,R541,R546,R547,R548,R549,R553,R555,R556,R557,R559,R560,R617,R619,R622,R634,R635,R639,R649,R651,R654,R666,R667,R671,R681,R683,R686,R698,R699,R703,R713,R715,R718,R730,R731,R735,R745,R747,R750,R762,R763,R767,R777,R779,R782,R794,R795,R799,R809,R811,R814,R826,R827,R831,R841,R843,R846,R858,R859,R863,R866,R1078,R1079,R1603,R1668,R1681,R1684,R1688,R1694,R1697,R1783,R2128,R2129,R2130,R2131,R2132,R2133,R2134,R2135,R2136,R2137,R2138,R2139,R2140,R2141,R2142,R2143,R2144,R2145,R2146,R2147,R2149 |  |  |  |  |  |  |
|  |  |  |  |  | 62 | 610107B00-012-G |  | RES,4.7KOhm,+/-5%,1/16W,G,SMD0402 | WALSIN TECHNOLOGY CORPORATION | WR04X472JTL |  | G |  |  |  |  |  |  |  |
|  |  |  |  |  | 62 | 610107B00-011-G |  | RES,4.7KOhm,+/-5%,1/16W,G,SMD0402 | YAGEO CORPORATION COMPONENT | RC0402JR-074K7L |  | G |  |  |  |  |  |  |  |
|  |  |  |  |  | 62 | 610107B00-044-G |  | RES,4.7KOhm,+/-5%,1/16W,G,SMD0402 | TA-I TECHNOLOGY CO., LTD | RM04JTN472 |  | G |  |  |  |  |  |  |  |
|  |  |  |  |  | 62 | 610107B00-024-G |  | RES,4.7KOhm,+/-5%,1/16W,G,SMD0402 | PANASONIC INDUSTRIAL CO.,LTD. | ERJ2GEJ472X |  | G |  |  |  |  |  |  |  |
|  |  |  |  |  | 62 | 610107B00-029-G |  | RES,4.7KOhm,+/-5%,1/16W,G,SMD0402 | VISHAY ENTER TECHNO LOGY.INC | CRCW04024K70JNED |  | G |  |  |  |  |  |  |  |
|  |  |  |  | 63 | 63 | 61010JY00-017-G | - | RES,220 Ohm,+/-5%,1/16W,G,SMD0402 | KOA SPEER ELECTRONICS, INC. | RK73B1ETTP221J | 10 | G | R12,R15,R1672,R1673,R1679,R1683,R1687,R1698,R1780,R1782 |  |  |  |  |  |  |
|  |  |  |  |  | 63 | 61010JY00-012-G |  | RES,220 Ohm,+/-5%,1/16W,G,SMD0402 | WALSIN TECHNOLOGY CORPORATION | WR04X221JTL |  | G |  |  |  |  |  |  |  |
|  |  |  |  |  | 63 | 61010JY00-011-G |  | RES,220 Ohm,+/-5%,1/16W,G,SMD0402 | YAGEO CORPORATION COMPONENT | RC0402JR-07220RL |  | G |  |  |  |  |  |  |  |
|  |  |  |  |  | 63 | 61010JY00-044-G |  | RES,220 Ohm,+/-5%,1/16W,G,SMD0402 | TA-I TECHNOLOGY CO., LTD | RM04JTN221 |  | G |  |  |  |  |  |  |  |
|  |  |  |  | 64 | 64 | 610101V00-017-G | K9572 | RES,22 Ohm,+/-5%,1/16W,G,SMD0402 | KOA SPEER ELECTRONICS, INC. | RK73B1ETTP220J | 40 | G | R106,R1740,R1741,R1742,R1743,R1744,R1745,R1746,R1747,R1748,R1749,R1750,R1751,R1752,R1753,R1754,R1755,R1756,R1757,R1758,R1759,R1760,R1761,R1762,R1763,R1764,R1765,R1766,R1767,R1768,R1769,R1770,R1771,R1772,R1773,R1774,R1775,R1776,R1777,R1778 |  |  |  |  |  |  |
|  |  |  |  |  | 64 | 610101V00-012-G |  | RES,22 Ohm,+/-5%,1/16W,G,SMD0402 | WALSIN TECHNOLOGY CORPORATION | WR04X220JTL |  | G |  |  |  |  |  |  |  |
|  |  |  |  |  | 64 | 610101V00-011-G |  | RES,22 Ohm,+/-5%,1/16W,G,SMD0402 | YAGEO CORPORATION COMPONENT | RC0402JR-0722RL |  | G |  |  |  |  |  |  |  |
|  |  |  |  |  | 64 | 610101V00-044-G |  | RES,22 Ohm,+/-5%,1/16W,G,SMD0402 | TA-I TECHNOLOGY CO., LTD | RM04JTN220 |  | G |  |  |  |  |  |  |  |
|  |  |  |  |  | 64 | 610101V00-024-G |  | RES,22 Ohm,+/-5%,1/16W,G,SMD0402 | PANASONIC INDUSTRIAL CO.,LTD. | ERJ2GEJ220X |  | G |  |  |  |  |  |  |  |
|  |  |  |  | 65 | 65 | 610118100-017-G | - | RES,1.4KOhm,+/-1%,1/16W,G,SMD0402 | KOA SPEER ELECTRONICS, INC. | RK73H1ETTP1401F | 2 | G | R251,R252 |  |  |  |  |  |  |
|  |  |  |  |  | 65 | 610118100-012-G |  | RES,1.4KOhm,+/-1%,1/16W,G,SMD0402 | WALSIN TECHNOLOGY CORPORATION | WR04X1401FTL |  | G |  |  |  |  |  |  |  |
|  |  |  |  |  | 65 | 610118100-011-G |  | RES,1.4KOhm,+/-1%,1/16W,G,SMD0402 | YAGEO CORPORATION COMPONENT | RC0402FR-071K4L |  | G |  |  |  |  |  |  |  |
|  |  |  |  |  | 65 | 610118100-044-G |  | RES,1.4KOhm,+/-1%,1/16W,G,SMD0402 | TA-I TECHNOLOGY CO., LTD | RM04FTN1401 |  | G |  |  |  |  |  |  |  |
|  |  |  |  |  | 65 | 610118100-024-G |  | RES,1.4KOhm,+/-1%,1/16W,G,SMD0402 | PANASONIC INDUSTRIAL CO.,LTD. | ERJ2RKF1401X |  | G |  |  |  |  |  |  |  |
|  |  |  |  | 66 | 66 | 61010BG00-017-G | RJ328 | RES,100 Ohm,+/-1%,1/10W,G,SMD0603 | KOA SPEER ELECTRONICS, INC. | RK73H1JTTD1000F | 72 | G | R313,R317,R319,R330,R332,R335,R410,R412,R415,R426,R428,R431,R442,R444,R447,R458,R459,R463,R474,R476,R479,R490,R491,R495,R616,R618,R621,R632,R633,R637,R648,R650,R653,R664,R665,R669,R680,R682,R685,R696,R697,R701,R712,R714,R717,R728,R729,R733,R744,R746,R749,R760,R761,R765,R776,R778,R781,R792,R793,R797,R808,R810,R813,R824,R825,R829,R840,R842,R845,R856,R857,R861 |  |  |  |  |  |  |
|  |  |  |  |  | 66 | 61010BG00-012-G |  | RES,100 Ohm,+/-1%,1/10W,G,SMD0603 | WALSIN TECHNOLOGY CORPORATION | WR06X1000FTL |  | G |  |  |  |  |  |  |  |
|  |  |  |  |  | 66 | 61010BG00-011-G |  | RES,100 Ohm,+/-1%,1/10W,G,SMD0603 | YAGEO CORPORATION COMPONENT | RC0603FR-07100RL |  | G |  |  |  |  |  |  |  |
|  |  |  |  | 67 | 67 | 61011QA00-017-G | - | RES,24KOhm,+/-5%,1/16W,G,SMD0402 | KOA SPEER ELECTRONICS, INC. | RK73B1ETTP243J | 24 | G | R314,R327,R407,R423,R439,R454,R471,R486,R613,R628,R645,R660,R677,R692,R709,R724,R741,R756,R773,R788,R805,R820,R837,R852 |  |  |  |  |  |  |
|  |  |  |  |  | 67 | 61011QA00-011-G |  | RES,24KOhm,+/-5%,1/16W,G,SMD0402 | YAGEO CORPORATION COMPONENT | RC0402JR-0724KL |  | G |  |  |  |  |  |  |  |
|  |  |  |  |  | 67 | 61011QA00-012-G |  | RES,24KOhm,+/-5%,1/16W,G,SMD0402 | WALSIN TECHNOLOGY CORPORATION | WR04X243JTL |  | G |  |  |  |  |  |  |  |
|  |  |  |  |  | 67 | 61011QA00-044-G |  | RES,24KOhm,+/-5%,1/16W,G,SMD0402 | TA-I TECHNOLOGY CO., LTD | RM04JTN243 |  | G |  |  |  |  |  |  |  |
|  |  |  |  | 68 | 68 | 610115Y00-017-G | - | RES,16.2KOhm,+/-1%,1/16W,G,SMD0402 | KOA SPEER ELECTRONICS, INC. | RK73H1ETTP1622F | 24 | G | R318,R326,R406,R422,R438,R455,R470,R487,R612,R629,R644,R661,R676,R693,R708,R725,R740,R757,R772,R789,R804,R821,R836,R853 |  |  |  |  |  |  |
|  |  |  |  |  | 68 | 610115Y00-011-G |  | RES,16.2KOhm,+/-1%,1/16W,G,SMD0402 | YAGEO CORPORATION COMPONENT | RC0402FR-0716K2L |  | G |  |  |  |  |  |  |  |
|  |  |  |  |  | 68 | 610115Y00-012-G |  | RES,16.2KOhm,+/-1%,1/16W,G,SMD0402 | WALSIN TECHNOLOGY CORPORATION | WR04X1622FTL |  | G |  |  |  |  |  |  |  |
|  |  |  |  |  | 68 | 610115Y00-044-G |  | RES,16.2KOhm,+/-1%,1/16W,G,SMD0402 | TA-I TECHNOLOGY CO., LTD | RM04FTN1622 |  | G |  |  |  |  |  |  |  |
|  |  |  |  |  | 68 | 610115Y00-024-G |  | RES,16.2KOhm,+/-1%,1/16W,G,SMD0402 | PANASONIC INDUSTRIAL CO.,LTD. | ERJ2RKF1622X |  | G |  |  |  |  |  |  |  |
|  |  |  |  |  | 68 | 610115Y00-029-G |  | RES,16.2KOhm,+/-1%,1/16W,G,SMD0402 | VISHAY ENTER TECHNO LOGY.INC | CRCW040216K2FKED |  | G |  |  |  |  |  |  |  |
|  |  |  |  | 69 | 69 | 61100LQ00-017-G |  | RES,20KOhm,+/-1%,1/16W,G,SMD0402 | KOA SPEER ELECTRONICS, INC. | RN731ETTP2002F50 | 44 | G | R348,R1522,R1523,R1524,R1525,R1526,R1527,R1528,R1529,R1530,R1531,R1532,R1533,R1534,R1535,R1536,R1537,R1538,R1539,R1540,R1541,R1542,R1543,R1544,R1545,R1546,R1547,R1548,R1549,R1550,R1551,R1552,R1553,R1554,R1555,R1556,R1557,R1558,R1559,R1560,R1561,R1563,R1565,R1567 |  |  |  |  |  |  |
|  |  |  |  |  | 69 | 61100LQ00-011-G |  | RES,20KOhm,+/-1%,1/16W,G,SMD0402 | YAGEO CORPORATION COMPONENT | RT0402FRE0720KL |  | G |  |  |  |  |  |  |  |
|  |  |  |  |  | 69 | 61100LQ00-044-G |  | RES,20KOhm,+/-1%,1/16W,G,SMD0402 | TA-I TECHNOLOGY CO., LTD | RB04FTS2002 |  | G |  |  |  |  |  |  |  |
|  |  |  |  |  | 69 | 61100LQ00-012-G |  | RES,20KOhm,+/-1%,1/16W,G,SMD0402 | WALSIN TECHNOLOGY CORPORATION | WF04T2002FTL |  | G |  |  |  |  |  |  |  |
|  |  |  |  | 70 | 70 | 610114J00-017-G | - | RES,2KOhm,+/-1%,1/16W,G,SMD0402 | KOA SPEER ELECTRONICS, INC. | RK73H1ETTP2001F | 5 | G | R501,R502,R508,R544,R545 |  |  |  |  |  |  |
|  |  |  |  |  | 70 | 610114J00-012-G |  | RES,2KOhm,+/-1%,1/16W,G,SMD0402 | WALSIN TECHNOLOGY CORPORATION | WR04X2001FTL |  | G |  |  |  |  |  |  |  |
|  |  |  |  |  | 70 | 610114J00-011-G |  | RES,2KOhm,+/-1%,1/16W,G,SMD0402 | YAGEO CORPORATION COMPONENT | RC0402FR-072KL |  | G |  |  |  |  |  |  |  |
|  |  |  |  |  | 70 | 610114J00-044-G |  | RES,2KOhm,+/-1%,1/16W,G,SMD0402 | TA-I TECHNOLOGY CO., LTD | RM04FTN2001 |  | G |  |  |  |  |  |  |  |
|  |  |  |  |  | 70 | 610114J00-024-G |  | RES,2KOhm,+/-1%,1/16W,G,SMD0402 | PANASONIC INDUSTRIAL CO.,LTD. | ERJ2RKF2001X |  | G |  |  |  |  |  |  |  |
|  |  |  |  |  | 70 | 610114J00-029-G |  | RES,2KOhm,+/-1%,1/16W,G,SMD0402 | VISHAY ENTER TECHNO LOGY.INC | CRCW04022K00FKED |  | G |  |  |  |  |  |  |  |
|  |  |  |  | 71 | 71 | 610100T00-017-G |  | RES,1KOhm,+/-5%,1/16W,G,SMD0402 | KOA SPEER ELECTRONICS, INC. | RK73B1ETTP102J | 41 | G | R515,R517,R518,R519,R521,R522,R523,R524,R558,R561,R562,R564,R565,R566,R567,R1314,R1786,R1789,R1790,R1792,R1794,R1797,R1798,R1801,R1802,R1805,R1806,R1809,R1810,R1813,R1814,R1817,R1818,R1821,R1822,R1825,R1826,R1829,R1830,R2052,R2082 |  |  |  |  |  |  |
|  |  |  |  |  | 71 | 610100T00-012-G |  | RES,1KOhm,+/-5%,1/16W,G,SMD0402 | WALSIN TECHNOLOGY CORPORATION | WR04X102JTL |  | G |  |  |  |  |  |  |  |
|  |  |  |  |  | 71 | 610100T00-011-G |  | RES,1KOhm,+/-5%,1/16W,G,SMD0402 | YAGEO CORPORATION COMPONENT | RC0402JR-071KL |  | G |  |  |  |  |  |  |  |
|  |  |  |  |  | 71 | 610100T00-044-G |  | RES,1KOhm,+/-5%,1/16W,G,SMD0402 | TA-I TECHNOLOGY CO., LTD | RM04JTN102 |  | G |  |  |  |  |  |  |  |
|  |  |  |  |  | 71 | 610100T00-024-G |  | RES,1KOhm,+/-5%,1/16W,G,SMD0402 | PANASONIC INDUSTRIAL CO.,LTD. | ERJ2GEJ102X |  | G |  |  |  |  |  |  |  |
|  |  |  |  | 72 | 72 | 61010L300-017-G | - | RES,1KOhm,+/-1%,1/16W,G,SMD0402 | KOA SPEER ELECTRONICS, INC. | RK73H1ETTP1001F | 10 | G | R525,R532,R865,R1072,R1073,R1074,R1077,R1438,R1439,R1440 |  |  |  |  |  |  |
|  |  |  |  |  | 72 | 61010L300-012-G |  | RES,1KOhm,+/-1%,1/16W,G,SMD0402 | WALSIN TECHNOLOGY CORPORATION | WR04X1001FTL |  | G |  |  |  |  |  |  |  |
|  |  |  |  |  | 72 | 61010L300-011-G |  | RES,1KOhm,+/-1%,1/16W,G,SMD0402 | YAGEO CORPORATION COMPONENT | RC0402FR-071KL |  | G |  |  |  |  |  |  |  |
|  |  |  |  |  | 72 | 61010L300-044-G |  | RES,1KOhm,+/-1%,1/16W,G,SMD0402 | TA-I TECHNOLOGY CO., LTD | RM04FTN1001 |  | G |  |  |  |  |  |  |  |
|  |  |  |  |  | 72 | 61010L300-024-G |  | RES,1KOhm,+/-1%,1/16W,G,SMD0402 | PANASONIC INDUSTRIAL CO.,LTD. | ERJ2RKF1001X |  | G |  |  |  |  |  |  |  |
|  |  |  |  |  | 72 | 61010L300-029-G |  | RES,1KOhm,+/-1%,1/16W,G,SMD0402 | VISHAY ENTER TECHNO LOGY.INC | CRCW04021K00FKED |  | G |  |  |  |  |  |  |  |
|  |  |  |  | 73 | 73 | 61010PS00-017-G | - | RES,200KOhm,+/-1%,1/16W,G,SMD0402 | KOA SPEER ELECTRONICS, INC. | RK73H1ETTP2003F | 2 | G | R526,R533 |  |  |  |  |  |  |
|  |  |  |  |  | 73 | 61010PS00-012-G |  | RES,200KOhm,+/-1%,1/16W,G,SMD0402 | WALSIN TECHNOLOGY CORPORATION | WR04X2003FTL |  | G |  |  |  |  |  |  |  |
|  |  |  |  |  | 73 | 61010PS00-011-G |  | RES,200KOhm,+/-1%,1/16W,G,SMD0402 | YAGEO CORPORATION COMPONENT | RC0402FR-07200KL |  | G |  |  |  |  |  |  |  |
|  |  |  |  |  | 73 | 61010PS00-044-G |  | RES,200KOhm,+/-1%,1/16W,G,SMD0402 | TA-I TECHNOLOGY CO., LTD | RM04FTN2003 |  | G |  |  |  |  |  |  |  |
|  |  |  |  | 74 | 74 | 61011BW00-017-G |  | RES,1.2KOhm,+/-1%,1/16W,G,SMD0402 | KOA SPEER ELECTRONICS, INC. | RK73H1ETTP1201F | 2 | G | R529,R535 |  |  |  |  |  |  |
|  |  |  |  |  | 74 | 61011BW00-012-G |  | RES,1.2KOhm,+/-1%,1/16W,G,SMD0402 | WALSIN TECHNOLOGY CORPORATION | WR04X1201FTL |  | G |  |  |  |  |  |  |  |
|  |  |  |  |  | 74 | 61011BW00-011-G |  | RES,1.2KOhm,+/-1%,1/16W,G,SMD0402 | YAGEO CORPORATION COMPONENT | RC0402FR-071K2L |  | G |  |  |  |  |  |  |  |
|  |  |  |  |  | 74 | 61011BW00-044-G |  | RES,1.2KOhm,+/-1%,1/16W,G,SMD0402 | TA-I TECHNOLOGY CO., LTD | RM04FTN1201 |  | G |  |  |  |  |  |  |  |
|  |  |  |  | 75 | 75 | 610116V00-017-G | - | RES,232KOhm,+/-1%,1/16W,G,SMD0402 | KOA SPEER ELECTRONICS, INC. | RK73H1ETTP2323F | 1 | G | R530 |  |  |  |  |  |  |
|  |  |  |  |  | 75 | 610116V00-012-G |  | RES,232KOhm,+/-1%,1/16W,G,SMD0402 | WALSIN TECHNOLOGY CORPORATION | WR04X2323FTL |  | G |  |  |  |  |  |  |  |
|  |  |  |  |  | 75 | 610116V00-011-G |  | RES,232KOhm,+/-1%,1/16W,G,SMD0402 | YAGEO CORPORATION COMPONENT | RC0402FR-07232KL |  | G |  |  |  |  |  |  |  |
|  |  |  |  |  | 75 | 610116V00-044-G |  | RES,232KOhm,+/-1%,1/16W,G,SMD0402 | TA-I TECHNOLOGY CO., LTD | RM04FTN2323 |  | G |  |  |  |  |  |  |  |
|  |  |  |  | 76 | 76 | 610116B00-017-G |  | RES,180KOhm,+/-1%,1/16W,G,SMD0402 | KOA SPEER ELECTRONICS, INC. | RK73H1ETTP1803F | 1 | G | R534 |  |  |  |  |  |  |
|  |  |  |  |  | 76 | 610116B00-012-G |  | RES,180KOhm,+/-1%,1/16W,G,SMD0402 | WALSIN TECHNOLOGY CORPORATION | WR04X1803FTL |  | G |  |  |  |  |  |  |  |
|  |  |  |  |  | 76 | 610116B00-011-G |  | RES,180KOhm,+/-1%,1/16W,G,SMD0402 | YAGEO CORPORATION COMPONENT | RC0402FR-07180KL |  | G |  |  |  |  |  |  |  |
|  |  |  |  |  | 76 | 610116B00-044-G |  | RES,180KOhm,+/-1%,1/16W,G,SMD0402 | TA-I TECHNOLOGY CO., LTD | RM04FTN1803 |  | G |  |  |  |  |  |  |  |
|  |  |  |  | 77 | 77 | 61011BQ00-017-G | - | RES,2.2 Ohm,+/-5%,1/16W,G,SMD0402 | KOA SPEER ELECTRONICS, INC. | RK73B1ETTP2R2J | 2 | G | R540,R583 |  |  |  |  |  |  |
|  |  |  |  |  | 77 | 61011BQ00-011-G |  | RES,2.2 Ohm,+/-5%,1/16W,G,SMD0402 | YAGEO CORPORATION COMPONENT | RC0402JR-072R2L |  | G |  |  |  |  |  |  |  |
|  |  |  |  |  | 77 | 61011BQ00-012-G |  | RES,2.2 Ohm,+/-5%,1/16W,G,SMD0402 | WALSIN TECHNOLOGY CORPORATION | WR04X2R2JTL |  | G |  |  |  |  |  |  |  |
|  |  |  |  |  | 77 | 61011BQ00-044-G |  | RES,2.2 Ohm,+/-5%,1/16W,G,SMD0402 | TA-I TECHNOLOGY CO., LTD | RM04JTN2R2 |  | G |  |  |  |  |  |  |  |
|  |  |  |  | 78 | 78 | 610108300-017-G | - | RES,0 Ohm,+/-5%,1/10W,G,SMD0603 | KOA SPEER ELECTRONICS, INC. | RK73Z1JTTD | 2 | G | R542,R585 |  |  |  |  |  |  |
|  |  |  |  |  | 78 | 610108300-012-G |  | RES,0 Ohm,+/-5%,1/10W,G,SMD0603 | WALSIN TECHNOLOGY CORPORATION | WR06X000PTL |  | G |  |  |  |  |  |  |  |
|  |  |  |  |  | 78 | 610108300-011-G |  | RES,0 Ohm,+/-5%,1/10W,G,SMD0603 | YAGEO CORPORATION COMPONENT | RC0603JR-070RL |  | G |  |  |  |  |  |  |  |
|  |  |  |  |  | 78 | 610108300-044-G |  | RES,0 Ohm,+/-5%,1/10W,G,SMD0603 | TA-I TECHNOLOGY CO., LTD | RM06JTN0 |  | G |  |  |  |  |  |  |  |
|  |  |  |  |  | 78 | 610108300-024-G |  | RES,0 Ohm,+/-5%,1/10W,G,SMD0603 | PANASONIC INDUSTRIAL CO.,LTD. | ERJ3GEY0R00V |  | G |  |  |  |  |  |  |  |
|  |  |  |  | 79 | 79 | 61010FE00-017-G | - | RES,100 Ohm,+/-1%,1/16W,G,SMD0402 | KOA SPEER ELECTRONICS, INC. | RK73H1ETTP1000F | 1 | G | R543 |  |  |  |  |  |  |
|  |  |  |  |  | 79 | 61010FE00-012-G |  | RES,100 Ohm,+/-1%,1/16W,G,SMD0402 | WALSIN TECHNOLOGY CORPORATION | WR04X1000FTL |  | G |  |  |  |  |  |  |  |
|  |  |  |  |  | 79 | 61010FE00-011-G |  | RES,100 Ohm,+/-1%,1/16W,G,SMD0402 | YAGEO CORPORATION COMPONENT | RC0402FR-07100RL |  | G |  |  |  |  |  |  |  |
|  |  |  |  |  | 79 | 61010FE00-044-G |  | RES,100 Ohm,+/-1%,1/16W,G,SMD0402 | TA-I TECHNOLOGY CO., LTD | RM04FTN1000 |  | G |  |  |  |  |  |  |  |
|  |  |  |  | 80 | 80 | 610118400-017-G |  | RES,27 Ohm,+/-1%,1/16W,G,SMD0402 | KOA SPEER ELECTRONICS, INC. | RK73H1ETTP27R0F | 32 | G | R817,R818,R828,R830,R832,R833,R834,R860,R867,R1443,R1444,R1445,R1446,R1447,R1448,R1458,R1459,R1460,R1461,R1462,R1463,R1464,R1465,R1466,R1467,R1468,R1469,R1470,R1471,R1472,R1473,R1604 |  |  |  |  |  |  |
|  |  |  |  |  | 80 | 610118400-012-G |  | RES,27 Ohm,+/-1%,1/16W,G,SMD0402 | WALSIN TECHNOLOGY CORPORATION | WR04X27R0FTL |  | G |  |  |  |  |  |  |  |
|  |  |  |  |  | 80 | 610118400-011-G |  | RES,27 Ohm,+/-1%,1/16W,G,SMD0402 | YAGEO CORPORATION COMPONENT | RC0402FR-0727RL |  | G |  |  |  |  |  |  |  |
|  |  |  |  |  | 80 | 610118400-044-G |  | RES,27 Ohm,+/-1%,1/16W,G,SMD0402 | TA-I TECHNOLOGY CO., LTD | RM04FTN27R0 |  | G |  |  |  |  |  |  |  |
|  |  |  |  | 81 | 81 | 610113A00-017-G | - | RES,2.2 Ohm,+/-5%,1/2W,G,SMD1210 | KOA SPEER ELECTRONICS, INC. | RK73B2ETTD2R2J | 24 | G | R874,R876,R878,R880,R882,R884,R886,R888,R890,R892,R894,R896,R898,R900,R902,R904,R906,R908,R910,R912,R914,R916,R918,R920 |  |  |  |  |  |  |
|  |  |  |  |  | 81 | 610113A00-012-G |  | RES,2.2 Ohm,+/-5%,1/2W,G,SMD1210 | WALSIN TECHNOLOGY CORPORATION | WF10P2R2JTL |  | G |  |  |  |  |  |  |  |
|  |  |  |  |  | 81 | 610113A00-011-G |  | RES,2.2 Ohm,+/-5%,1/2W,G,SMD1210 | YAGEO CORPORATION COMPONENT | RC1210JR-072R2L |  | G |  |  |  |  |  |  |  |
|  |  |  |  | 82 | 82 | 61015K700-017-G |  | RES,3.3 Ohm,+/-5%,1/2W,G,SMD1210 | KOA SPEER ELECTRONICS, INC. | RK73B2ETTD3R3J | 24 | G | R875,R877,R879,R881,R883,R885,R887,R889,R891,R893,R895,R897,R899,R901,R903,R905,R907,R909,R911,R913,R915,R917,R919,R921 |  |  |  |  |  |  |
|  |  |  |  |  | 82 | 61015K700-011-G |  | RES,3.3 Ohm,+/-5%,1/2W,G,SMD1210 | YAGEO CORPORATION COMPONENT | RC1210JR-073R3L |  | G |  |  |  |  |  |  |  |
|  |  |  |  | 83 | 83 | 61011MV00-017-G |  | RES,510 Ohm,+/-1%,1/16W,G,SMD0402 | KOA SPEER ELECTRONICS, INC. | RK73H1ETTP5100F | 24 | G | R1313,R1785,R1787,R1788,R1791,R1793,R1795,R1796,R1799,R1800,R1803,R1804,R1807,R1808,R1811,R1812,R1815,R1816,R1819,R1820,R1823,R1824,R1827,R1828 |  |  |  |  |  |  |
|  |  |  |  |  | 83 | 61011MV00-012-G |  | RES,510 Ohm,+/-1%,1/16W,G,SMD0402 | WALSIN TECHNOLOGY CORPORATION | WR04X5100FTL |  | G |  |  |  |  |  |  |  |
|  |  |  |  |  | 83 | 61011MV00-011-G |  | RES,510 Ohm,+/-1%,1/16W,G,SMD0402 | YAGEO CORPORATION COMPONENT | RC0402FR-07510RL |  | G |  |  |  |  |  |  |  |
|  |  |  |  |  | 83 | 61011MV00-044-G |  | RES,510 Ohm,+/-1%,1/16W,G,SMD0402 | TA-I TECHNOLOGY CO., LTD | RM04FTN5100 |  | G |  |  |  |  |  |  |  |
|  |  |  |  | 84 | 84 | 610107L00-017-G |  | RES,1 Ohm,+/-5%,1/10W,G,SMD0603 | KOA SPEER ELECTRONICS, INC. | RK73B1JTTD1R0J | 2 | G | R1408,R1449 |  |  |  |  |  |  |
|  |  |  |  |  | 84 | 610107L00-011-G |  | RES,1 Ohm,+/-5%,1/10W,G,SMD0603 | YAGEO CORPORATION COMPONENT | RC0603JR-071RL |  | G |  |  |  |  |  |  |  |
|  |  |  |  |  | 84 | 610107L00-012-G |  | RES,1 Ohm,+/-5%,1/10W,G,SMD0603 | WALSIN TECHNOLOGY CORPORATION | WR06X1R0JTL |  | G |  |  |  |  |  |  |  |
|  |  |  |  |  | 84 | 610107L00-044-G |  | RES,1 Ohm,+/-5%,1/10W,G,SMD0603 | TA-I TECHNOLOGY CO., LTD | RM06JTN1R0 |  | G |  |  |  |  |  |  |  |
|  |  |  |  | 85 | 85 | 61100AH00-017-G |  | RES,10KOhm,+/-0.5%,1/16W,G,SMD0402 | KOA SPEER ELECTRONICS, INC. | RN731ETTP1002D25 | 12 | G | R2049,R2050,R2051,R2062,R2063,R2064,R2071,R2075,R2077,R2079,R2083,R2084 |  |  |  |  |  |  |
|  |  |  |  | 86 | 86 | 610154800-017-G |  | RES,1 Ohm,+/-5%,1/8W,G,SMD0402 | KOA SPEER ELECTRONICS, INC. | SG73P1ETTP1R0J | 1 | G | R2060 |  |  |  |  |  |  |
|  |  |  |  |  | 86 | 610154800-011-G |  | RES,1 Ohm,+/-5%,1/8W,G,SMD0402 | YAGEO CORPORATION COMPONENT | RC0402JR-7W1RL |  | G |  |  |  |  |  |  |  |
|  |  |  |  |  | 86 | 610154800-012-G |  | RES,1 Ohm,+/-5%,1/8W,G,SMD0402 | WALSIN TECHNOLOGY CORPORATION | WF04P1R0 JTL |  | G |  |  |  |  |  |  |  |
|  |  |  |  | 87 | 87 | 310101400-031-G | - | IC,Gate&Inverter,74LVC1G08GW,1.65~5.5V,G,SOT353-5,SMD | NXP SEMICONDUCTORS | 74LVC1G08GW | 3 | G | U_AND1,U_AND2,U5 |  |  |  |  |  |  |
|  |  |  |  | 88 | 88 | 41040HW00-191-G |  | EEPROM,AT24C02D-SSHM-T,1.7~3.6V,2K,I2C,G,SOIC-8,SMD | ATMEL CORPORATION | AT24C02D-SSHM-T | 1 | G | U_BP_FRU1 |  |  |  |  |  |  |
|  |  |  |  | 89 | 89 | 21050LL00-217-G | - | IC,IDT,9ZXL0831AKLFT,G,VFQFPN-48,SMD | INTEGRATED DEVICE TECHNOLOGY | 9ZXL0831AKLFT | 2 | G | U_Clock_B,U_Clock_A |  |  |  |  |  |  |
|  |  |  |  | 90 | 90 | 311004V00-223-G |  | Logic IC,Translator,PCA9617ADMR2G,Vcca=0.8V~5.5V,Vccb=2.2V~5.5V,102ns,Micro8,8P,G | ON SEMICONDUCTOR CORP | PCA9617ADMR2G | 2 | G | U_I2C_RE1,U_I2C_RE2 |  |  |  |  |  |  |
|  |  |  |  | 91 | 91 | 31030YF00-252-G |  | Logic IC,Switch,PI4MSD5V9546ALEX,1.65V~5.5V,0.3ns,TSSOP,16P,G | PERICOM SEMICONDUCTOR CORP | PI4MSD5V9546ALEX | 5 | G | U_MUX1,U_MUX2,U_MUX3,U_MUX4,U_MUX5 |  |  |  |  |  |  |
|  |  |  |  | 92 | 92 | 32040P400-399-G |  | IC,Voltage sensor,SLG4N020VTR,G,TDFN-8,SMD | SILEGO | SLG4N020VTR | 1 | G | U_RESET |  |  |  |  |  |  |
|  |  |  |  | 93 | 93 | 32022WB00-173-G |  | IC,Power Controller,MAX6420UK16+T,G,SOT-23-5P,SMD | MAXIM INTEGRATED PRODUCTS, INC. | MAX6420UK16+T | 1 | G | U_RESET1 |  |  |  |  |  |  |
|  |  |  |  | 94 | 94 | 21081NC00-432-G |  | IC,LSI,500021009,A2,G,TFBGA-141,SMD | LSI LOGIC CORPORATION | 500021009 | 2 | G | U_SF1,U_SF2 |  |  |  |  |  |  |
|  |  |  |  | 95 | 95 | 32040J800-183-G |  | IC,Temp Sensor,TMP75AIDGKR,N/A,G,MSOP-8,SMD | TEXAS INSTRUMENTS | TMP75AIDGKR | 1 | G | U_TMP1 |  |  |  |  |  |  |
|  |  |  |  | 96 | 96 | 310700500-183-G |  | IC,Decoder&Encoder,PCA9306DCUR,0~5V,G,VSSOP-8,SMD | TEXAS INSTRUMENTS | PCA9306DCUR | 2 | G | U1,U2 |  |  |  |  |  |  |
|  |  |  |  | 97 | 97 | 21050RJ00-217-G |  | IC,IDT,9FGL0651BKILFT,G,VFQFPN-40,SMD | INTEGRATED DEVICE TECHNOLOGY | 9FGL0651BKILFT | 1 | G | U29 |  |  |  |  |  |  |
|  |  |  |  | 98 | 98 | 310501200-183-G | - | IC,Buffer,SN74LVC1G07DCKR,1.65~5.5V,G,SC70-5,SMD | TEXAS INSTRUMENTS | SN74LVC1G07DCKR | 1 | G | U209 |  |  |  |  |  |  |
|  |  |  |  | 99 | 99 | 220106A00-413-G |  | IC,PLD,10M08SCU169C8G,3.3V,116MHz,G,BGA-169,SMD | ALTERA CORPORATION | 10M08SCU169C8G | 1 | G | U248 |  |  |  |  |  |  |
|  |  |  |  | 100 | 100 | 71012HD00-100-G |  | XTAL,25MHz,+/-20ppm,8pF,G,SMD | TXC CORPORATION | 7V25000054 | 1 | G | X7 |  |  |  |  |  |  |
|  |  |  |  | 101 | 101 | 2A5910Q00-HYM-G |  | SMT NUT,CARBON STEEL,G,FIVETECH,82-059-01-022-01-RL | Fivetech Technology Inc. | 82-059-01-022-01-RL | 10 | G | H1,H2,H3,H4,H7,H8,H9,H10,H30,H31 |  |  |  |  |  |  |
|  |  |  |  | 102 | 102 | 340718A00-245-G |  | CONN,SAS,V/T,0.6mm,30u,G,SMD-74 | AMPHENOL SHANGHAI CORP. | U10-B074-250T | 10 | G | JSAS1,JPCIE1,JSAS2,JPCIE2,JSAS3,JPCIE3,JPCIE4,JPCIE5,JPCIE6,JPCIE7 |  |  |  |  |  |  |
|  |  |  |  | 103 | 103 | 3406B6F00-317-G |  | CONN,Header,WTB,2X3,R/A,Bla,2.5mm,15u,G,SMD-6 | MOLEX INCORPORATED | 15-91-2065 | 1 | G | J_CPLD_JTAG |  |  |  |  |  |  |
|  |  |  |  | 104 | 104 | 340655900-245-G | - | CONN,Header,WTB,1X4,R/A,Whi,1mm,G,SMD-4 | AMPHENOL SHANGHAI CORP. | G846A04100Y1EU | 1 | G | J_LED1 |  |  |  |  |  |  |
|  |  |  |  | 105 | 105 | 340313H00-600-G | - | CONN,PCIE,V/T,Bla,0.8mm,30u,G,SMD-68 | FOXCONN TECHNOLOGY CO.,LTD. | LU25683-A001-9H | 24 | G | J_NVME01,J_NVME02,J_NVME03,J_NVME04,J_NVME05,J_NVME06,J_NVME07,J_NVME08,J_NVME09,J_NVME10,J_NVME11,J_NVME12,J_NVME13,J_NVME14,J_NVME15,J_NVME16,J_NVME17,J_NVME18,J_NVME19,J_NVME20,J_NVME21,J_NVME22,J_NVME23,J_NVME00 |  |  |  |  |  |  |
|  |  |  |  | 106 | 106 | 3406B3H00-317-G |  | CONN,Header,Power,2X8,V/T,Bla,3mm,G,SMD-16 | MOLEX INCORPORATED | 43045-1618 | 1 | G | J1 |  |  |  |  |  |  |
